(kicad_pcb
	(version 20260206)
	(generator "pcbnew")
	(generator_version "10.0")
	(general
		(thickness 1.6)
		(legacy_teardrops no)
	)
	(paper "A4")
	(title_block
		(title "panther-plus-userver — 13130-1b_20150205.brd")
		(comment 1 "Honey Badger (Wiwynn) / footprints 1031-1038 of 1509")
	)
	(layers
		(0 "F.Cu" signal "TOP")
		(4 "In1.Cu" signal "L2")
		(6 "In2.Cu" signal "L3")
		(8 "In3.Cu" signal "L4")
		(10 "In4.Cu" signal "L5")
		(12 "In5.Cu" signal "L6")
		(14 "In6.Cu" signal "L7")
		(16 "In7.Cu" signal "L8")
		(18 "In8.Cu" signal "L9")
		(20 "In9.Cu" signal "L10")
		(22 "In10.Cu" signal "L11")
		(2 "B.Cu" signal "BOTTOM")
		(9 "F.Adhes" user "F.Adhesive")
		(11 "B.Adhes" user "B.Adhesive")
		(13 "F.Paste" user "Package Geometry/Pastemask Top")
		(15 "B.Paste" user "Package Geometry/Pastemask Bottom")
		(5 "F.SilkS" user "Ref Des/Silkscreen Top")
		(7 "B.SilkS" user "Ref Des/Silkscreen Bottom")
		(1 "F.Mask" user "Board Geometry/Soldermask Top")
		(3 "B.Mask" user "Board Geometry/Soldermask Bottom")
		(17 "Dwgs.User" user "User.Drawings")
		(19 "Cmts.User" user "User.Comments")
		(21 "Eco1.User" user "User.Eco1")
		(23 "Eco2.User" user "User.Eco2")
		(25 "Edge.Cuts" user "Board Geometry/Outline")
		(27 "Margin" user)
		(31 "F.CrtYd" user "Package Geometry/Place Bound Top")
		(29 "B.CrtYd" user "Package Geometry/Place Bound Bottom")
		(35 "F.Fab" user "Ref Des/Assembly Top")
		(33 "B.Fab" user "Ref Des/Assembly Bottom")
	)
	(footprint ""
		(layer "B.Cu")
		(at 74.041 -31.75 90)
		(property "Reference" "R119"
			(at 0 0 90)
			(layer "B.SilkS")
			(hide yes)
			(effects
				(font
					(size 1.27 1.27)
				)
				(justify mirror)
			)
		)
		(property "Value" "10KR2F-2-GP"
			(at -0.064008 -3.993896 90)
			(unlocked yes)
			(layer "B.Fab")
			(hide yes)
			(effects
				(font
					(size 1.016 1.016)
					(thickness 0.1524)
				)
				(justify mirror)
			)
		)
		(property "Device Type" "R402H16"
			(at -0.064008 -5.517896 90)
			(unlocked yes)
			(layer "B.Fab")
			(hide yes)
			(effects
				(font
					(size 1.016 1.016)
					(thickness 0.1524)
				)
				(justify mirror)
			)
		)
		(duplicate_pad_numbers_are_jumpers no)
		(fp_rect
			(start 0.381 0.8382)
			(end -0.381 -0.8382)
			(stroke
				(width 0)
				(type default)
			)
			(fill no)
			(layer "B.CrtYd")
		)
		(fp_rect
			(start 0.381 0.8382)
			(end -0.381 -0.8382)
			(stroke
				(width 0)
				(type default)
			)
			(fill no)
			(layer "B.Fab")
		)
		(pad "1" smd custom
			(at 0 -0.4318 270)
			(size 0.127 0.127)
			(layers "B.Cu" "B.Mask" "B.Paste")
			(net "P3V3_CPU")
			(options
				(clearance outline)
				(anchor circle)
			)
			(primitives
				(gr_poly
					(pts
						(arc
							(start -0.2032 0.2794)
							(mid -0.239121 0.264521)
							(end -0.254 0.2286)
						)
						(arc
							(start -0.254 -0.2286)
							(mid -0.239121 -0.264521)
							(end -0.2032 -0.2794)
						)
						(arc
							(start 0.2032 -0.2794)
							(mid 0.239121 -0.264521)
							(end 0.254 -0.2286)
						)
						(arc
							(start 0.254 0.2286)
							(mid 0.239121 0.264521)
							(end 0.2032 0.2794)
						)
					)
					(width 0)
					(fill yes)
				)
			)
		)
		(pad "2" smd custom
			(at 0 0.4318 270)
			(size 0.127 0.127)
			(layers "B.Cu" "B.Mask" "B.Paste")
			(net "GBE_MDIO_DATA0")
			(options
				(clearance outline)
				(anchor circle)
			)
			(primitives
				(gr_poly
					(pts
						(arc
							(start -0.2032 0.2794)
							(mid -0.239121 0.264521)
							(end -0.254 0.2286)
						)
						(arc
							(start -0.254 -0.2286)
							(mid -0.239121 -0.264521)
							(end -0.2032 -0.2794)
						)
						(arc
							(start 0.2032 -0.2794)
							(mid 0.239121 -0.264521)
							(end 0.254 -0.2286)
						)
						(arc
							(start 0.254 0.2286)
							(mid 0.239121 0.264521)
							(end 0.2032 0.2794)
						)
					)
					(width 0)
					(fill yes)
				)
			)
		)
	)
	(footprint ""
		(layer "B.Cu")
		(at 52.6796 -23.5712 180)
		(property "Reference" "R454"
			(at 0 0 0)
			(layer "B.SilkS")
			(hide yes)
			(effects
				(font
					(size 1.27 1.27)
				)
				(justify mirror)
			)
		)
		(property "Value" "432R2F-GP"
			(at -1.7907 -1.1176 180)
			(unlocked yes)
			(layer "B.Fab")
			(hide yes)
			(effects
				(font
					(size 1.016 1.016)
					(thickness 0.1524)
				)
				(justify mirror)
			)
		)
		(property "Device Type" "R402H16"
			(at -1.7907 -2.6416 180)
			(unlocked yes)
			(layer "B.Fab")
			(hide yes)
			(effects
				(font
					(size 1.016 1.016)
					(thickness 0.1524)
				)
				(justify mirror)
			)
		)
		(duplicate_pad_numbers_are_jumpers no)
		(fp_rect
			(start 0.381 0.8382)
			(end -0.381 -0.8382)
			(stroke
				(width 0)
				(type default)
			)
			(fill no)
			(layer "B.CrtYd")
		)
		(fp_rect
			(start 0.381 0.8382)
			(end -0.381 -0.8382)
			(stroke
				(width 0)
				(type default)
			)
			(fill no)
			(layer "B.Fab")
		)
		(pad "1" smd custom
			(at 0 -0.4318)
			(size 0.127 0.127)
			(layers "B.Cu" "B.Mask" "B.Paste")
			(net "CLKBUFF_IREF")
			(options
				(clearance outline)
				(anchor circle)
			)
			(primitives
				(gr_poly
					(pts
						(arc
							(start -0.2032 0.2794)
							(mid -0.239121 0.264521)
							(end -0.254 0.2286)
						)
						(arc
							(start -0.254 -0.2286)
							(mid -0.239121 -0.264521)
							(end -0.2032 -0.2794)
						)
						(arc
							(start 0.2032 -0.2794)
							(mid 0.239121 -0.264521)
							(end 0.254 -0.2286)
						)
						(arc
							(start 0.254 0.2286)
							(mid 0.239121 0.264521)
							(end 0.2032 0.2794)
						)
					)
					(width 0)
					(fill yes)
				)
			)
		)
		(pad "2" smd custom
			(at 0 0.4318)
			(size 0.127 0.127)
			(layers "B.Cu" "B.Mask" "B.Paste")
			(net "GND")
			(options
				(clearance outline)
				(anchor circle)
			)
			(primitives
				(gr_poly
					(pts
						(arc
							(start -0.2032 0.2794)
							(mid -0.239121 0.264521)
							(end -0.254 0.2286)
						)
						(arc
							(start -0.254 -0.2286)
							(mid -0.239121 -0.264521)
							(end -0.2032 -0.2794)
						)
						(arc
							(start 0.2032 -0.2794)
							(mid 0.239121 -0.264521)
							(end 0.254 -0.2286)
						)
						(arc
							(start 0.254 0.2286)
							(mid 0.239121 0.264521)
							(end 0.2032 0.2794)
						)
					)
					(width 0)
					(fill yes)
				)
			)
		)
	)
	(footprint ""
		(layer "B.Cu")
		(at 137.922 -45.466 90)
		(property "Reference" "C164"
			(at 0 0 90)
			(layer "B.SilkS")
			(hide yes)
			(effects
				(font
					(size 1.27 1.27)
				)
				(justify mirror)
			)
		)
		(property "Value" "SCD1U10V2KX-5GP"
			(at -1.1811 -2.7051 90)
			(unlocked yes)
			(layer "B.Fab")
			(hide yes)
			(effects
				(font
					(size 1.016 1.016)
					(thickness 0.1524)
				)
				(justify mirror)
			)
		)
		(property "Device Type" "C402H22"
			(at -1.1811 -4.2291 90)
			(unlocked yes)
			(layer "B.Fab")
			(hide yes)
			(effects
				(font
					(size 1.016 1.016)
					(thickness 0.1524)
				)
				(justify mirror)
			)
		)
		(duplicate_pad_numbers_are_jumpers no)
		(fp_rect
			(start 0.381 0.7366)
			(end -0.381 -0.7366)
			(stroke
				(width 0)
				(type default)
			)
			(fill no)
			(layer "B.CrtYd")
		)
		(fp_rect
			(start 0.381 0.7366)
			(end -0.381 -0.7366)
			(stroke
				(width 0)
				(type default)
			)
			(fill no)
			(layer "B.Fab")
		)
		(pad "1" smd custom
			(at 0 -0.4572 270)
			(size 0.1143 0.1143)
			(layers "B.Cu" "B.Mask" "B.Paste")
			(net "P1V2_FPGA_D")
			(options
				(clearance outline)
				(anchor circle)
			)
			(primitives
				(gr_poly
					(pts
						(arc
							(start -0.254 0.1778)
							(mid -0.239121 0.213721)
							(end -0.2032 0.2286)
						)
						(arc
							(start 0.2032 0.2286)
							(mid 0.239121 0.213721)
							(end 0.254 0.1778)
						)
						(arc
							(start 0.254 -0.1778)
							(mid 0.239121 -0.213721)
							(end 0.2032 -0.2286)
						)
						(arc
							(start -0.2032 -0.2286)
							(mid -0.239121 -0.213721)
							(end -0.254 -0.1778)
						)
					)
					(width 0)
					(fill yes)
				)
			)
		)
		(pad "2" smd custom
			(at 0 0.4572 270)
			(size 0.1143 0.1143)
			(layers "B.Cu" "B.Mask" "B.Paste")
			(net "GND")
			(options
				(clearance outline)
				(anchor circle)
			)
			(primitives
				(gr_poly
					(pts
						(arc
							(start -0.254 0.1778)
							(mid -0.239121 0.213721)
							(end -0.2032 0.2286)
						)
						(arc
							(start 0.2032 0.2286)
							(mid 0.239121 0.213721)
							(end 0.254 0.1778)
						)
						(arc
							(start 0.254 -0.1778)
							(mid 0.239121 -0.213721)
							(end 0.2032 -0.2286)
						)
						(arc
							(start -0.2032 -0.2286)
							(mid -0.239121 -0.213721)
							(end -0.254 -0.1778)
						)
					)
					(width 0)
					(fill yes)
				)
			)
		)
	)
	(footprint ""
		(layer "B.Cu")
		(at 103.251 -34.052002 90)
		(property "Reference" "C214"
			(at 0 0 90)
			(layer "B.SilkS")
			(hide yes)
			(effects
				(font
					(size 1.27 1.27)
				)
				(justify mirror)
			)
		)
		(property "Value" "SC2D2U10V2KX-GP"
			(at -1.1811 -2.7051 90)
			(unlocked yes)
			(layer "B.Fab")
			(hide yes)
			(effects
				(font
					(size 1.016 1.016)
					(thickness 0.1524)
				)
				(justify mirror)
			)
		)
		(property "Device Type" "C402H22"
			(at -1.1811 -4.2291 90)
			(unlocked yes)
			(layer "B.Fab")
			(hide yes)
			(effects
				(font
					(size 1.016 1.016)
					(thickness 0.1524)
				)
				(justify mirror)
			)
		)
		(duplicate_pad_numbers_are_jumpers no)
		(fp_rect
			(start 0.381 0.7366)
			(end -0.381 -0.7366)
			(stroke
				(width 0)
				(type default)
			)
			(fill no)
			(layer "B.CrtYd")
		)
		(fp_rect
			(start 0.381 0.7366)
			(end -0.381 -0.7366)
			(stroke
				(width 0)
				(type default)
			)
			(fill no)
			(layer "B.Fab")
		)
		(pad "1" smd custom
			(at 0 -0.4572 270)
			(size 0.1143 0.1143)
			(layers "B.Cu" "B.Mask" "B.Paste")
			(net "P1V0")
			(options
				(clearance outline)
				(anchor circle)
			)
			(primitives
				(gr_poly
					(pts
						(arc
							(start -0.254 0.1778)
							(mid -0.239121 0.213721)
							(end -0.2032 0.2286)
						)
						(arc
							(start 0.2032 0.2286)
							(mid 0.239121 0.213721)
							(end 0.254 0.1778)
						)
						(arc
							(start 0.254 -0.1778)
							(mid 0.239121 -0.213721)
							(end 0.2032 -0.2286)
						)
						(arc
							(start -0.2032 -0.2286)
							(mid -0.239121 -0.213721)
							(end -0.254 -0.1778)
						)
					)
					(width 0)
					(fill yes)
				)
			)
		)
		(pad "2" smd custom
			(at 0 0.4572 270)
			(size 0.1143 0.1143)
			(layers "B.Cu" "B.Mask" "B.Paste")
			(net "GND")
			(options
				(clearance outline)
				(anchor circle)
			)
			(primitives
				(gr_poly
					(pts
						(arc
							(start -0.254 0.1778)
							(mid -0.239121 0.213721)
							(end -0.2032 0.2286)
						)
						(arc
							(start 0.2032 0.2286)
							(mid 0.239121 0.213721)
							(end 0.254 0.1778)
						)
						(arc
							(start 0.254 -0.1778)
							(mid 0.239121 -0.213721)
							(end 0.2032 -0.2286)
						)
						(arc
							(start -0.2032 -0.2286)
							(mid -0.239121 -0.213721)
							(end -0.254 -0.1778)
						)
					)
					(width 0)
					(fill yes)
				)
			)
		)
	)
	(footprint ""
		(layer "B.Cu")
		(at 17.653 -56.388 -90)
		(property "Reference" "PC2"
			(at 0 0 90)
			(layer "B.SilkS")
			(hide yes)
			(effects
				(font
					(size 1.27 1.27)
				)
				(justify mirror)
			)
		)
		(property "Value" "SC470P50V2KX-3GP"
			(at -1.8923 -1.2065 270)
			(unlocked yes)
			(layer "B.Fab")
			(hide yes)
			(effects
				(font
					(size 1.016 1.016)
					(thickness 0.1524)
				)
				(justify mirror)
			)
		)
		(property "Device Type" "C402H22"
			(at -1.8923 -2.7305 270)
			(unlocked yes)
			(layer "B.Fab")
			(hide yes)
			(effects
				(font
					(size 1.016 1.016)
					(thickness 0.1524)
				)
				(justify mirror)
			)
		)
		(duplicate_pad_numbers_are_jumpers no)
		(fp_rect
			(start 0.381 0.7366)
			(end -0.381 -0.7366)
			(stroke
				(width 0)
				(type default)
			)
			(fill no)
			(layer "B.CrtYd")
		)
		(fp_rect
			(start 0.381 0.7366)
			(end -0.381 -0.7366)
			(stroke
				(width 0)
				(type default)
			)
			(fill no)
			(layer "B.Fab")
		)
		(pad "1" smd custom
			(at 0 -0.4572 90)
			(size 0.1143 0.1143)
			(layers "B.Cu" "B.Mask" "B.Paste")
			(net "VR_PVNN_FB_RC1")
			(options
				(clearance outline)
				(anchor circle)
			)
			(primitives
				(gr_poly
					(pts
						(arc
							(start -0.254 0.1778)
							(mid -0.239121 0.213721)
							(end -0.2032 0.2286)
						)
						(arc
							(start 0.2032 0.2286)
							(mid 0.239121 0.213721)
							(end 0.254 0.1778)
						)
						(arc
							(start 0.254 -0.1778)
							(mid 0.239121 -0.213721)
							(end 0.2032 -0.2286)
						)
						(arc
							(start -0.2032 -0.2286)
							(mid -0.239121 -0.213721)
							(end -0.254 -0.1778)
						)
					)
					(width 0)
					(fill yes)
				)
			)
		)
		(pad "2" smd custom
			(at 0 0.4572 90)
			(size 0.1143 0.1143)
			(layers "B.Cu" "B.Mask" "B.Paste")
			(net "VR_PVNN_VSEN_R")
			(options
				(clearance outline)
				(anchor circle)
			)
			(primitives
				(gr_poly
					(pts
						(arc
							(start -0.254 0.1778)
							(mid -0.239121 0.213721)
							(end -0.2032 0.2286)
						)
						(arc
							(start 0.2032 0.2286)
							(mid 0.239121 0.213721)
							(end 0.254 0.1778)
						)
						(arc
							(start 0.254 -0.1778)
							(mid 0.239121 -0.213721)
							(end 0.2032 -0.2286)
						)
						(arc
							(start -0.2032 -0.2286)
							(mid -0.239121 -0.213721)
							(end -0.254 -0.1778)
						)
					)
					(width 0)
					(fill yes)
				)
			)
		)
	)
	(footprint ""
		(layer "B.Cu")
		(at 90.2081 -34.2138 90)
		(property "Reference" "C211"
			(at 0 0 90)
			(layer "B.SilkS")
			(hide yes)
			(effects
				(font
					(size 1.27 1.27)
				)
				(justify mirror)
			)
		)
		(property "Value" "SC1U10V2KX-1GP"
			(at -1.1811 -2.7051 90)
			(unlocked yes)
			(layer "B.Fab")
			(hide yes)
			(effects
				(font
					(size 1.016 1.016)
					(thickness 0.1524)
				)
				(justify mirror)
			)
		)
		(property "Device Type" "C402H22"
			(at -1.1811 -4.2291 90)
			(unlocked yes)
			(layer "B.Fab")
			(hide yes)
			(effects
				(font
					(size 1.016 1.016)
					(thickness 0.1524)
				)
				(justify mirror)
			)
		)
		(duplicate_pad_numbers_are_jumpers no)
		(fp_rect
			(start 0.381 0.7366)
			(end -0.381 -0.7366)
			(stroke
				(width 0)
				(type default)
			)
			(fill no)
			(layer "B.CrtYd")
		)
		(fp_rect
			(start 0.381 0.7366)
			(end -0.381 -0.7366)
			(stroke
				(width 0)
				(type default)
			)
			(fill no)
			(layer "B.Fab")
		)
		(pad "1" smd custom
			(at 0 -0.4572 270)
			(size 0.1143 0.1143)
			(layers "B.Cu" "B.Mask" "B.Paste")
			(net "P1V0")
			(options
				(clearance outline)
				(anchor circle)
			)
			(primitives
				(gr_poly
					(pts
						(arc
							(start -0.254 0.1778)
							(mid -0.239121 0.213721)
							(end -0.2032 0.2286)
						)
						(arc
							(start 0.2032 0.2286)
							(mid 0.239121 0.213721)
							(end 0.254 0.1778)
						)
						(arc
							(start 0.254 -0.1778)
							(mid 0.239121 -0.213721)
							(end 0.2032 -0.2286)
						)
						(arc
							(start -0.2032 -0.2286)
							(mid -0.239121 -0.213721)
							(end -0.254 -0.1778)
						)
					)
					(width 0)
					(fill yes)
				)
			)
		)
		(pad "2" smd custom
			(at 0 0.4572 270)
			(size 0.1143 0.1143)
			(layers "B.Cu" "B.Mask" "B.Paste")
			(net "GND")
			(options
				(clearance outline)
				(anchor circle)
			)
			(primitives
				(gr_poly
					(pts
						(arc
							(start -0.254 0.1778)
							(mid -0.239121 0.213721)
							(end -0.2032 0.2286)
						)
						(arc
							(start 0.2032 0.2286)
							(mid 0.239121 0.213721)
							(end 0.254 0.1778)
						)
						(arc
							(start 0.254 -0.1778)
							(mid 0.239121 -0.213721)
							(end 0.2032 -0.2286)
						)
						(arc
							(start -0.2032 -0.2286)
							(mid -0.239121 -0.213721)
							(end -0.254 -0.1778)
						)
					)
					(width 0)
					(fill yes)
				)
			)
		)
	)
	(footprint ""
		(layer "B.Cu")
		(at 99.949 -21.9202)
		(property "Reference" "R380"
			(at 0 0 0)
			(layer "B.SilkS")
			(hide yes)
			(effects
				(font
					(size 1.27 1.27)
				)
				(justify mirror)
			)
		)
		(property "Value" "23D7R2F-GP"
			(at -0.064008 -3.993896 0)
			(unlocked yes)
			(layer "B.Fab")
			(hide yes)
			(effects
				(font
					(size 1.016 1.016)
					(thickness 0.1524)
				)
				(justify mirror)
			)
		)
		(property "Device Type" "R402H16"
			(at -0.064008 -5.517896 0)
			(unlocked yes)
			(layer "B.Fab")
			(hide yes)
			(effects
				(font
					(size 1.016 1.016)
					(thickness 0.1524)
				)
				(justify mirror)
			)
		)
		(duplicate_pad_numbers_are_jumpers no)
		(fp_rect
			(start 0.381 0.8382)
			(end -0.381 -0.8382)
			(stroke
				(width 0)
				(type default)
			)
			(fill no)
			(layer "B.CrtYd")
		)
		(fp_rect
			(start 0.381 0.8382)
			(end -0.381 -0.8382)
			(stroke
				(width 0)
				(type default)
			)
			(fill no)
			(layer "B.Fab")
		)
		(pad "1" smd custom
			(at 0 -0.4318 180)
			(size 0.127 0.127)
			(layers "B.Cu" "B.Mask" "B.Paste")
			(net "M_B_CMDPU")
			(options
				(clearance outline)
				(anchor circle)
			)
			(primitives
				(gr_poly
					(pts
						(arc
							(start -0.2032 0.2794)
							(mid -0.239121 0.264521)
							(end -0.254 0.2286)
						)
						(arc
							(start -0.254 -0.2286)
							(mid -0.239121 -0.264521)
							(end -0.2032 -0.2794)
						)
						(arc
							(start 0.2032 -0.2794)
							(mid 0.239121 -0.264521)
							(end 0.254 -0.2286)
						)
						(arc
							(start 0.254 0.2286)
							(mid 0.239121 0.264521)
							(end 0.2032 0.2794)
						)
					)
					(width 0)
					(fill yes)
				)
			)
		)
		(pad "2" smd custom
			(at 0 0.4318 180)
			(size 0.127 0.127)
			(layers "B.Cu" "B.Mask" "B.Paste")
			(net "GND")
			(options
				(clearance outline)
				(anchor circle)
			)
			(primitives
				(gr_poly
					(pts
						(arc
							(start -0.2032 0.2794)
							(mid -0.239121 0.264521)
							(end -0.254 0.2286)
						)
						(arc
							(start -0.254 -0.2286)
							(mid -0.239121 -0.264521)
							(end -0.2032 -0.2794)
						)
						(arc
							(start 0.2032 -0.2794)
							(mid 0.239121 -0.264521)
							(end 0.254 -0.2286)
						)
						(arc
							(start 0.254 0.2286)
							(mid 0.239121 0.264521)
							(end 0.2032 0.2794)
						)
					)
					(width 0)
					(fill yes)
				)
			)
		)
	)
	(footprint ""
		(layer "B.Cu")
		(at 60.198 -14.9352)
		(property "Reference" "C317"
			(at 0 0 0)
			(layer "B.SilkS")
			(hide yes)
			(effects
				(font
					(size 1.27 1.27)
				)
				(justify mirror)
			)
		)
		(property "Value" "SCD1U10V2KX-5GP"
			(at -1.8923 -1.2065 0)
			(unlocked yes)
			(layer "B.Fab")
			(hide yes)
			(effects
				(font
					(size 1.016 1.016)
					(thickness 0.1524)
				)
				(justify mirror)
			)
		)
		(property "Device Type" "C402H22"
			(at -1.8923 -2.7305 0)
			(unlocked yes)
			(layer "B.Fab")
			(hide yes)
			(effects
				(font
					(size 1.016 1.016)
					(thickness 0.1524)
				)
				(justify mirror)
			)
		)
		(duplicate_pad_numbers_are_jumpers no)
		(fp_rect
			(start 0.381 0.7366)
			(end -0.381 -0.7366)
			(stroke
				(width 0)
				(type default)
			)
			(fill no)
			(layer "B.CrtYd")
		)
		(fp_rect
			(start 0.381 0.7366)
			(end -0.381 -0.7366)
			(stroke
				(width 0)
				(type default)
			)
			(fill no)
			(layer "B.Fab")
		)
		(pad "1" smd custom
			(at 0 -0.4572 180)
			(size 0.1143 0.1143)
			(layers "B.Cu" "B.Mask" "B.Paste")
			(net "P3V3_STBY")
			(options
				(clearance outline)
				(anchor circle)
			)
			(primitives
				(gr_poly
					(pts
						(arc
							(start -0.254 0.1778)
							(mid -0.239121 0.213721)
							(end -0.2032 0.2286)
						)
						(arc
							(start 0.2032 0.2286)
							(mid 0.239121 0.213721)
							(end 0.254 0.1778)
						)
						(arc
							(start 0.254 -0.1778)
							(mid 0.239121 -0.213721)
							(end 0.2032 -0.2286)
						)
						(arc
							(start -0.2032 -0.2286)
							(mid -0.239121 -0.213721)
							(end -0.254 -0.1778)
						)
					)
					(width 0)
					(fill yes)
				)
			)
		)
		(pad "2" smd custom
			(at 0 0.4572 180)
			(size 0.1143 0.1143)
			(layers "B.Cu" "B.Mask" "B.Paste")
			(net "GND")
			(options
				(clearance outline)
				(anchor circle)
			)
			(primitives
				(gr_poly
					(pts
						(arc
							(start -0.254 0.1778)
							(mid -0.239121 0.213721)
							(end -0.2032 0.2286)
						)
						(arc
							(start 0.2032 0.2286)
							(mid 0.239121 0.213721)
							(end 0.254 0.1778)
						)
						(arc
							(start 0.254 -0.1778)
							(mid 0.239121 -0.213721)
							(end 0.2032 -0.2286)
						)
						(arc
							(start -0.2032 -0.2286)
							(mid -0.239121 -0.213721)
							(end -0.254 -0.1778)
						)
					)
					(width 0)
					(fill yes)
				)
			)
		)
	)
)
